# T6G (Grand Teton) — schematic netlist excerpt (pin names and nets, part order shuffled) for the footprints in the layout excerpt that follows; sources: Cadence DE-HDL packaged netlist, KiCad conversion of 04192023_DAF0TMB3IC0_F0TG_MB_C_brd_V02_OCP.brd

R6164  Q_RES  1K 1% CHIP  pkg 0402LF  page 112 : A = FM_P2E_BUF2_EQB1 ; B = GND
PC159  Q_CAP  560PF 50V 10% EMPTY  pkg C0402  page 205 : A = SW_PVDDIO_P0_SW2 ; B = SW_PVDDIO_P0_SW2_RC

(kicad_pcb
	(version 20260206)
	(generator "pcbnew")
	(generator_version "10.0")
	(general
		(thickness 1.6)
		(legacy_teardrops no)
	)
	(paper "A4")
	(title_block
		(title "04192023_DAF0TMB3IC0_F0TG_MB_C_brd_V02_OCP.brd")
		(comment 1 "Grand Teton / footprints 2106-2107 of 8354")
	)
	(layers
		(0 "F.Cu" signal "TOP")
		(4 "In1.Cu" signal "GND")
		(6 "In2.Cu" signal "IN1")
		(8 "In3.Cu" signal "GND1")
		(10 "In4.Cu" signal "IN2")
		(12 "In5.Cu" signal "GND2")
		(14 "In6.Cu" signal "IN3")
		(16 "In7.Cu" signal "GND3")
		(18 "In8.Cu" signal "VCC")
		(20 "In9.Cu" signal "VCC1")
		(22 "In10.Cu" signal "GND4")
		(24 "In11.Cu" signal "IN4")
		(26 "In12.Cu" signal "GND5")
		(28 "In13.Cu" signal "IN5")
		(30 "In14.Cu" signal "GND6")
		(32 "In15.Cu" signal "IN6")
		(34 "In16.Cu" signal "GND7")
		(2 "B.Cu" signal "BOTTOM")
		(9 "F.Adhes" user "F.Adhesive")
		(11 "B.Adhes" user "B.Adhesive")
		(13 "F.Paste" user "Package Geometry/Pastemask Top")
		(15 "B.Paste" user "Package Geometry/Pastemask Bottom")
		(5 "F.SilkS" user "Ref Des/Silkscreen Top")
		(7 "B.SilkS" user "Ref Des/Silkscreen Bottom")
		(1 "F.Mask" user "Board Geometry/Soldermask Top")
		(3 "B.Mask" user "Board Geometry/Soldermask Bottom")
		(17 "Dwgs.User" user "User.Drawings")
		(19 "Cmts.User" user "User.Comments")
		(21 "Eco1.User" user "User.Eco1")
		(23 "Eco2.User" user "User.Eco2")
		(25 "Edge.Cuts" user "Board Geometry/Outline")
		(27 "Margin" user)
		(31 "F.CrtYd" user "Package Geometry/Place Bound Top")
		(29 "B.CrtYd" user "Package Geometry/Place Bound Bottom")
		(35 "F.Fab" user "Ref Des/Assembly Top")
		(33 "B.Fab" user "Ref Des/Assembly Bottom")
	)
	(footprint ""
		(layer "F.Cu")
		(at 19.844258 -427.580298 90)
		(property "Reference" "R6164"
			(at 0 0 90)
			(layer "F.SilkS")
			(hide yes)
			(effects
				(font
					(size 1.27 1.27)
				)
			)
		)
		(property "Value" ""
			(at 0 0 90)
			(layer "F.Fab")
			(effects
				(font
					(size 1.27 1.27)
				)
			)
		)
		(duplicate_pad_numbers_are_jumpers no)
		(fp_line
			(start 0.7874 -0.4064)
			(end 0.7874 0.4064)
			(stroke
				(width 0.1524)
				(type default)
			)
			(layer "F.SilkS")
		)
		(fp_line
			(start -0.7874 -0.4064)
			(end 0.7874 -0.4064)
			(stroke
				(width 0.1524)
				(type default)
			)
			(layer "F.SilkS")
		)
		(fp_line
			(start 0.7874 0.4064)
			(end -0.7874 0.4064)
			(stroke
				(width 0.1524)
				(type default)
			)
			(layer "F.SilkS")
		)
		(fp_line
			(start -0.7874 0.4064)
			(end -0.7874 -0.4064)
			(stroke
				(width 0.1524)
				(type default)
			)
			(layer "F.SilkS")
		)
		(fp_line
			(start -0.12065 -0.305054)
			(end -0.12065 -0.2794)
			(stroke
				(width 0.1)
				(type default)
			)
			(layer "F.Fab")
		)
		(fp_line
			(start -0.67945 -0.305054)
			(end -0.12065 -0.305054)
			(stroke
				(width 0.1)
				(type default)
			)
			(layer "F.Fab")
		)
		(fp_line
			(start 0.67945 -0.3048)
			(end 0.67945 0.3048)
			(stroke
				(width 0.1)
				(type default)
			)
			(layer "F.Fab")
		)
		(fp_line
			(start 0.12065 -0.3048)
			(end 0.67945 -0.3048)
			(stroke
				(width 0.1)
				(type default)
			)
			(layer "F.Fab")
		)
		(fp_line
			(start 0.12065 -0.2794)
			(end 0.12065 -0.3048)
			(stroke
				(width 0.1)
				(type default)
			)
			(layer "F.Fab")
		)
		(fp_line
			(start -0.12065 -0.2794)
			(end 0.12065 -0.2794)
			(stroke
				(width 0.1)
				(type default)
			)
			(layer "F.Fab")
		)
		(fp_line
			(start 0.120396 0.2794)
			(end -0.12065 0.2794)
			(stroke
				(width 0.1)
				(type default)
			)
			(layer "F.Fab")
		)
		(fp_line
			(start -0.12065 0.2794)
			(end -0.12065 0.3048)
			(stroke
				(width 0.1)
				(type default)
			)
			(layer "F.Fab")
		)
		(fp_line
			(start 0.67945 0.3048)
			(end 0.120396 0.3048)
			(stroke
				(width 0.1)
				(type default)
			)
			(layer "F.Fab")
		)
		(fp_line
			(start 0.120396 0.3048)
			(end 0.120396 0.2794)
			(stroke
				(width 0.1)
				(type default)
			)
			(layer "F.Fab")
		)
		(fp_line
			(start -0.12065 0.3048)
			(end -0.67945 0.3048)
			(stroke
				(width 0.1)
				(type default)
			)
			(layer "F.Fab")
		)
		(fp_line
			(start -0.67945 0.3048)
			(end -0.67945 -0.305054)
			(stroke
				(width 0.1)
				(type default)
			)
			(layer "F.Fab")
		)
		(pad "1" smd circle
			(at -0.40005 0 90)
			(size 0 0)
			(layers "F.Cu" "F.Mask" "F.Paste")
			(net "FM_P2E_BUF2_EQB1")
		)
		(pad "2" smd circle
			(at 0.40005 0 90)
			(size 0 0)
			(layers "F.Cu" "F.Mask" "F.Paste")
			(net "GND")
		)
	)
	(footprint ""
		(layer "F.Cu")
		(at 288.314384 -343.712038 180)
		(property "Reference" "PC159"
			(at 0 0 180)
			(layer "F.SilkS")
			(hide yes)
			(effects
				(font
					(size 1.27 1.27)
				)
			)
		)
		(property "Value" ""
			(at 0 0 180)
			(layer "F.Fab")
			(effects
				(font
					(size 1.27 1.27)
				)
			)
		)
		(duplicate_pad_numbers_are_jumpers no)
		(fp_line
			(start 0.7874 0.4064)
			(end -0.7874 0.4064)
			(stroke
				(width 0.1524)
				(type default)
			)
			(layer "F.SilkS")
		)
		(fp_line
			(start 0.7874 -0.4064)
			(end 0.7874 0.4064)
			(stroke
				(width 0.1524)
				(type default)
			)
			(layer "F.SilkS")
		)
		(fp_line
			(start -0.7874 0.4064)
			(end -0.7874 -0.4064)
			(stroke
				(width 0.1524)
				(type default)
			)
			(layer "F.SilkS")
		)
		(fp_line
			(start -0.7874 -0.4064)
			(end 0.7874 -0.4064)
			(stroke
				(width 0.1524)
				(type default)
			)
			(layer "F.SilkS")
		)
		(fp_line
			(start 0.67945 0.3048)
			(end 0.120396 0.3048)
			(stroke
				(width 0.1)
				(type default)
			)
			(layer "F.Fab")
		)
		(fp_line
			(start 0.67945 -0.3048)
			(end 0.67945 0.3048)
			(stroke
				(width 0.1)
				(type default)
			)
			(layer "F.Fab")
		)
		(fp_line
			(start 0.12065 -0.2794)
			(end 0.12065 -0.3048)
			(stroke
				(width 0.1)
				(type default)
			)
			(layer "F.Fab")
		)
		(fp_line
			(start 0.12065 -0.3048)
			(end 0.67945 -0.3048)
			(stroke
				(width 0.1)
				(type default)
			)
			(layer "F.Fab")
		)
		(fp_line
			(start 0.120396 0.3048)
			(end 0.120396 0.2794)
			(stroke
				(width 0.1)
				(type default)
			)
			(layer "F.Fab")
		)
		(fp_line
			(start 0.120396 0.2794)
			(end -0.12065 0.2794)
			(stroke
				(width 0.1)
				(type default)
			)
			(layer "F.Fab")
		)
		(fp_line
			(start -0.12065 0.3048)
			(end -0.67945 0.3048)
			(stroke
				(width 0.1)
				(type default)
			)
			(layer "F.Fab")
		)
		(fp_line
			(start -0.12065 0.2794)
			(end -0.12065 0.3048)
			(stroke
				(width 0.1)
				(type default)
			)
			(layer "F.Fab")
		)
		(fp_line
			(start -0.12065 -0.2794)
			(end 0.12065 -0.2794)
			(stroke
				(width 0.1)
				(type default)
			)
			(layer "F.Fab")
		)
		(fp_line
			(start -0.12065 -0.305054)
			(end -0.12065 -0.2794)
			(stroke
				(width 0.1)
				(type default)
			)
			(layer "F.Fab")
		)
		(fp_line
			(start -0.67945 0.3048)
			(end -0.67945 -0.305054)
			(stroke
				(width 0.1)
				(type default)
			)
			(layer "F.Fab")
		)
		(fp_line
			(start -0.67945 -0.305054)
			(end -0.12065 -0.305054)
			(stroke
				(width 0.1)
				(type default)
			)
			(layer "F.Fab")
		)
		(pad "1" smd circle
			(at -0.40005 0 180)
			(size 0 0)
			(layers "F.Cu" "F.Mask" "F.Paste")
			(net "SW_PVDDIO_P0_SW2")
		)
		(pad "2" smd circle
			(at 0.40005 0 180)
			(size 0 0)
			(layers "F.Cu" "F.Mask" "F.Paste")
			(net "SW_PVDDIO_P0_SW2_RC")
		)
	)
)
